FILE_TYPE = MULTI_PHYS_TABLE;
PART 'W25Q128'
{=======================================================================================================================================================================================================================================}
:PACK_TYPE| MATERIAL | PART_NUMBER     = EnvComp                            | PART_NUMBER  | JEDEC_TYPE      | ALT_SYMBOLS       | DESCRIPTION                                           | CLASS | COMPONENT_TYPE | HEIGHT     | LPID     | SPEED_URL | Status |RPL| AML | Bus_Unit | Days ;
{========================================================================================================================================================================================================================================}
'SOIC16'  | 'IC'     | 'H12709-001'(!) = ''                                 | 'H12709-001' | 'SOI16_30_50IB' | ''                | '(USE SYM_3)IC,FLASH,128MB SPI NOR,SOIC,16'           | 'IC'  | 'SOIC'         | '0.104 IN' | '1353' | 'http://speed.intel.com:8081/speed/module/pdm/item/pdm_item_detail_direct.asp?item_cde=H12709-001&item_rev=01&url_param=unused' | '' | '' | '' | '' | '' 
'SOIC16'  | 'EMPTY'  | 'H12709-001'(!) = ''                                 | 'H12709-001' | 'SOI16_30_50IB' | ''                | '(USE SYM_3)IC,FLASH,128MB SPI NOR,SOIC,16'           | 'IO'  | 'SOIC'         | '0.104 IN' | '1353' | 'http://speed.intel.com:8081/speed/module/pdm/item/pdm_item_detail_direct.asp?item_cde=H12709-001&item_rev=01&url_param=unused' | '' | '' | '' | '' | ''
'SKT16'   | 'IC'     | 'H12709-001'(!) = ''                                 | 'H12709-001' | 'XSOI16_30_50IA'| ''                | '(USE SYM_3)IC,FLASH,128MB SPI NOR,SOIC,16'           | 'IC'  | 'SOIC'         | '0.104 IN' | ''     | 'http://speed.intel.com:8081/speed/module/pdm/item/pdm_item_detail_direct.asp?item_cde=H12709-001&item_rev=01&url_param=unused' | '' | '' | '' | '' | '' 
'SKT16'   | 'EMPTY'  | 'H12709-001'(!) = ''                                 | 'H12709-001' | 'XSOI16_30_50IA'| ''                | '(USE SYM_3)IC,FLASH,128MB SPI NOR,SOIC,16'           | 'IO'  | 'SOIC'         | '0.104 IN' | ''     | 'http://speed.intel.com:8081/speed/module/pdm/item/pdm_item_detail_direct.asp?item_cde=H12709-001&item_rev=01&url_param=unused' | '' | '' | '' | '' | '' 
END_PART
END.
